(kicad_pcb
	(version 20260206)
	(generator "pcbnew")
	(generator_version "10.0")
	(general
		(thickness 1.6)
		(legacy_teardrops no)
	)
	(paper "A4")
	(title_block
		(title "baseboard — 13948-1b.1110WZS1818.brd")
		(comment 1 "Honey Badger (Wiwynn) / footprints 58-63 of 2523")
	)
	(layers
		(0 "F.Cu" signal "TOP")
		(4 "In1.Cu" signal "L2GND")
		(6 "In2.Cu" signal "L3")
		(8 "In3.Cu" signal "L4VCC")
		(10 "In4.Cu" signal "L5VCC")
		(12 "In5.Cu" signal "L6")
		(14 "In6.Cu" signal "L7GND")
		(2 "B.Cu" signal "BOTTOM")
		(9 "F.Adhes" user "F.Adhesive")
		(11 "B.Adhes" user "B.Adhesive")
		(13 "F.Paste" user "Package Geometry/Pastemask Top")
		(15 "B.Paste" user "Package Geometry/Pastemask Bottom")
		(5 "F.SilkS" user "Ref Des/Silkscreen Top")
		(7 "B.SilkS" user "Ref Des/Silkscreen Bottom")
		(1 "F.Mask" user "Board Geometry/Soldermask Top")
		(3 "B.Mask" user "Board Geometry/Soldermask Bottom")
		(17 "Dwgs.User" user "User.Drawings")
		(19 "Cmts.User" user "User.Comments")
		(21 "Eco1.User" user "User.Eco1")
		(23 "Eco2.User" user "User.Eco2")
		(25 "Edge.Cuts" user "Board Geometry/Outline")
		(27 "Margin" user)
		(31 "F.CrtYd" user "Package Geometry/Place Bound Top")
		(29 "B.CrtYd" user "Package Geometry/Place Bound Bottom")
		(35 "F.Fab" user "Ref Des/Assembly Top")
		(33 "B.Fab" user "Ref Des/Assembly Bottom")
	)
	(footprint ""
		(layer "F.Cu")
		(at 261.239 -43.942 90)
		(property "Reference" "PR55"
			(at 0 0 90)
			(layer "F.SilkS")
			(hide yes)
			(effects
				(font
					(size 1.27 1.27)
				)
			)
		)
		(property "Value" "619KR2F-GP"
			(at 0.064008 -3.993896 90)
			(unlocked yes)
			(layer "F.Fab")
			(hide yes)
			(effects
				(font
					(size 1.016 1.016)
					(thickness 0.1524)
				)
			)
		)
		(property "Device Type" "R402H16"
			(at 0.064008 -5.517896 90)
			(unlocked yes)
			(layer "F.Fab")
			(hide yes)
			(effects
				(font
					(size 1.016 1.016)
					(thickness 0.1524)
				)
			)
		)
		(duplicate_pad_numbers_are_jumpers no)
		(fp_line
			(start 0.508 -0.9398)
			(end -0.508 -0.9398)
			(stroke
				(width 0.1524)
				(type default)
			)
			(layer "F.SilkS")
		)
		(fp_line
			(start -0.508 -0.9398)
			(end -0.508 0.9398)
			(stroke
				(width 0.1524)
				(type default)
			)
			(layer "F.SilkS")
		)
		(fp_rect
			(start -0.508 0.9398)
			(end 0.508 -0.9398)
			(stroke
				(width 0)
				(type default)
			)
			(fill no)
			(layer "F.CrtYd")
		)
		(fp_rect
			(start -0.508 0.9398)
			(end 0.508 -0.9398)
			(stroke
				(width 0)
				(type default)
			)
			(fill no)
			(layer "F.Fab")
		)
		(pad "1" smd custom
			(at 0 -0.4445 90)
			(size 0.1397 0.1397)
			(layers "F.Cu" "F.Mask" "F.Paste")
			(net "AGND_P1V8_STBY")
			(options
				(clearance outline)
				(anchor circle)
			)
			(primitives
				(gr_poly
					(pts
						(arc
							(start -0.1778 -0.2794)
							(mid -0.249642 -0.249642)
							(end -0.2794 -0.1778)
						)
						(arc
							(start -0.2794 0.1778)
							(mid -0.249642 0.249642)
							(end -0.1778 0.2794)
						)
						(arc
							(start 0.1778 0.2794)
							(mid 0.249642 0.249642)
							(end 0.2794 0.1778)
						)
						(arc
							(start 0.2794 -0.1778)
							(mid 0.249642 -0.249642)
							(end 0.1778 -0.2794)
						)
					)
					(width 0)
					(fill yes)
				)
			)
		)
		(pad "2" smd custom
			(at 0 0.4445 90)
			(size 0.1397 0.1397)
			(layers "F.Cu" "F.Mask" "F.Paste")
			(net "P1V8_STBY_RF")
			(options
				(clearance outline)
				(anchor circle)
			)
			(primitives
				(gr_poly
					(pts
						(arc
							(start -0.1778 -0.2794)
							(mid -0.249642 -0.249642)
							(end -0.2794 -0.1778)
						)
						(arc
							(start -0.2794 0.1778)
							(mid -0.249642 0.249642)
							(end -0.1778 0.2794)
						)
						(arc
							(start 0.1778 0.2794)
							(mid 0.249642 0.249642)
							(end 0.2794 0.1778)
						)
						(arc
							(start 0.2794 -0.1778)
							(mid 0.249642 -0.249642)
							(end 0.1778 -0.2794)
						)
					)
					(width 0)
					(fill yes)
				)
			)
		)
	)
	(footprint ""
		(layer "F.Cu")
		(at 307.086 -160.655)
		(property "Reference" "R471"
			(at 0 0 0)
			(layer "F.SilkS")
			(hide yes)
			(effects
				(font
					(size 1.27 1.27)
				)
			)
		)
		(property "Value" "0R2J-2-GP"
			(at 0.064008 -3.993896 0)
			(unlocked yes)
			(layer "F.Fab")
			(hide yes)
			(effects
				(font
					(size 1.016 1.016)
					(thickness 0.1524)
				)
			)
		)
		(property "Device Type" "R402H16"
			(at 0.064008 -5.517896 0)
			(unlocked yes)
			(layer "F.Fab")
			(hide yes)
			(effects
				(font
					(size 1.016 1.016)
					(thickness 0.1524)
				)
			)
		)
		(duplicate_pad_numbers_are_jumpers no)
		(fp_line
			(start -0.508 -0.9398)
			(end -0.508 0.9398)
			(stroke
				(width 0.1524)
				(type default)
			)
			(layer "F.SilkS")
		)
		(fp_line
			(start 0.508 -0.9398)
			(end -0.508 -0.9398)
			(stroke
				(width 0.1524)
				(type default)
			)
			(layer "F.SilkS")
		)
		(fp_rect
			(start -0.508 0.9398)
			(end 0.508 -0.9398)
			(stroke
				(width 0)
				(type default)
			)
			(fill no)
			(layer "F.CrtYd")
		)
		(fp_rect
			(start -0.508 0.9398)
			(end 0.508 -0.9398)
			(stroke
				(width 0)
				(type default)
			)
			(fill no)
			(layer "F.Fab")
		)
		(pad "1" smd custom
			(at 0 -0.4445)
			(size 0.1397 0.1397)
			(layers "F.Cu" "F.Mask" "F.Paste")
			(net "BMC0_SMB10_CLK")
			(options
				(clearance outline)
				(anchor circle)
			)
			(primitives
				(gr_poly
					(pts
						(arc
							(start -0.1778 -0.2794)
							(mid -0.249642 -0.249642)
							(end -0.2794 -0.1778)
						)
						(arc
							(start -0.2794 0.1778)
							(mid -0.249642 0.249642)
							(end -0.1778 0.2794)
						)
						(arc
							(start 0.1778 0.2794)
							(mid 0.249642 0.249642)
							(end 0.2794 0.1778)
						)
						(arc
							(start 0.2794 -0.1778)
							(mid 0.249642 -0.249642)
							(end 0.1778 -0.2794)
						)
					)
					(width 0)
					(fill yes)
				)
			)
		)
		(pad "2" smd custom
			(at 0 0.4445)
			(size 0.1397 0.1397)
			(layers "F.Cu" "F.Mask" "F.Paste")
			(net "BMC_I2C_SCL_10")
			(options
				(clearance outline)
				(anchor circle)
			)
			(primitives
				(gr_poly
					(pts
						(arc
							(start -0.1778 -0.2794)
							(mid -0.249642 -0.249642)
							(end -0.2794 -0.1778)
						)
						(arc
							(start -0.2794 0.1778)
							(mid -0.249642 0.249642)
							(end -0.1778 0.2794)
						)
						(arc
							(start 0.1778 0.2794)
							(mid 0.249642 0.249642)
							(end 0.2794 0.1778)
						)
						(arc
							(start 0.2794 -0.1778)
							(mid 0.249642 -0.249642)
							(end 0.1778 -0.2794)
						)
					)
					(width 0)
					(fill yes)
				)
			)
		)
	)
	(footprint ""
		(layer "F.Cu")
		(at 67.945 -51.054 180)
		(property "Reference" "SL7"
			(at 0 0 180)
			(layer "F.SilkS")
			(hide yes)
			(effects
				(font
					(size 1.27 1.27)
				)
			)
		)
		(property "Value" "MPZ2012S601AT-GP"
			(at 0 -4.2418 180)
			(unlocked yes)
			(layer "F.Fab")
			(hide yes)
			(effects
				(font
					(size 1.016 1.016)
					(thickness 0.1524)
				)
			)
		)
		(property "Device Type" "L805H42"
			(at 0 -5.7912 180)
			(unlocked yes)
			(layer "F.Fab")
			(hide yes)
			(effects
				(font
					(size 1.016 1.016)
					(thickness 0.1524)
				)
			)
		)
		(duplicate_pad_numbers_are_jumpers no)
		(fp_line
			(start 0.889 1.7018)
			(end -0.889 1.7018)
			(stroke
				(width 0.1524)
				(type default)
			)
			(layer "F.SilkS")
		)
		(fp_line
			(start 0.889 -1.7018)
			(end 0.889 1.7018)
			(stroke
				(width 0.1524)
				(type default)
			)
			(layer "F.SilkS")
		)
		(fp_line
			(start -0.889 1.7018)
			(end -0.889 -1.7018)
			(stroke
				(width 0.1524)
				(type default)
			)
			(layer "F.SilkS")
		)
		(fp_line
			(start -0.889 -1.7018)
			(end 0.889 -1.7018)
			(stroke
				(width 0.1524)
				(type default)
			)
			(layer "F.SilkS")
		)
		(fp_rect
			(start -0.9652 1.778)
			(end 0.9652 -1.778)
			(stroke
				(width 0)
				(type default)
			)
			(fill no)
			(layer "F.CrtYd")
		)
		(fp_rect
			(start -0.9652 1.778)
			(end 0.9652 -1.778)
			(stroke
				(width 0)
				(type default)
			)
			(fill no)
			(layer "F.Fab")
		)
		(pad "1" smd rect
			(at 0 -0.9652 180)
			(size 1.397 1.143)
			(layers "F.Cu" "F.Mask" "F.Paste")
			(net "SAS0_VDDH")
		)
		(pad "2" smd rect
			(at 0 0.9652 180)
			(size 1.397 1.143)
			(layers "F.Cu" "F.Mask" "F.Paste")
			(net "P1V8_C")
		)
	)
	(footprint ""
		(layer "F.Cu")
		(at 96.52 -227.711 90)
		(property "Reference" "U188"
			(at 0 0 90)
			(layer "F.SilkS")
			(hide yes)
			(effects
				(font
					(size 1.27 1.27)
				)
			)
		)
		(property "Value" "PCA9552PW-GP"
			(at 0 -12.1412 90)
			(unlocked yes)
			(layer "F.Fab")
			(hide yes)
			(effects
				(font
					(size 1.016 1.016)
					(thickness 0.1524)
				)
			)
		)
		(property "Device Type" "TSOIC24H44"
			(at 0 -13.6652 90)
			(unlocked yes)
			(layer "F.Fab")
			(hide yes)
			(effects
				(font
					(size 1.016 1.016)
					(thickness 0.1524)
				)
			)
		)
		(duplicate_pad_numbers_are_jumpers no)
		(fp_line
			(start 3.683 -1.778)
			(end 3.683 1.778)
			(stroke
				(width 0.1524)
				(type default)
			)
			(layer "F.SilkS")
		)
		(fp_line
			(start -4.1148 -1.778)
			(end 3.683 -1.778)
			(stroke
				(width 0.1524)
				(type default)
			)
			(layer "F.SilkS")
		)
		(fp_line
			(start -4.1148 -1.778)
			(end -4.1148 1.778)
			(stroke
				(width 0.1524)
				(type default)
			)
			(layer "F.SilkS")
		)
		(fp_line
			(start -3.8354 0)
			(end -4.1148 -0.2794)
			(stroke
				(width 0.1524)
				(type default)
			)
			(layer "F.SilkS")
		)
		(fp_line
			(start -3.8354 0)
			(end -4.1148 0.2794)
			(stroke
				(width 0.1524)
				(type default)
			)
			(layer "F.SilkS")
		)
		(fp_line
			(start 3.683 1.778)
			(end -4.1148 1.778)
			(stroke
				(width 0.1524)
				(type default)
			)
			(layer "F.SilkS")
		)
		(fp_line
			(start -4.0386 1.778)
			(end -4.0386 3.556)
			(stroke
				(width 0.3556)
				(type default)
			)
			(layer "F.SilkS")
		)
		(fp_poly
			(pts
				(xy -3.7592 -1.778) (xy 3.683 -1.778) (xy 3.683 1.778) (xy -3.7592 1.778)
			)
			(stroke
				(width 0)
				(type default)
			)
			(fill yes)
			(layer "F.SilkS")
		)
		(fp_poly
			(pts
				(xy -4.22656 3.81) (xy 4.22656 3.81) (xy 4.22656 -3.81) (xy -4.22656 -3.81)
			)
			(stroke
				(width 0)
				(type default)
			)
			(fill no)
			(layer "F.CrtYd")
		)
		(fp_poly
			(pts
				(xy -4.22656 -3.81) (xy 4.22656 -3.81) (xy 4.22656 3.81) (xy -4.22656 3.81)
			)
			(stroke
				(width 0)
				(type default)
			)
			(fill no)
			(layer "F.Fab")
		)
		(pad "1" smd rect
			(at -3.57632 2.8194 90)
			(size 0.3556 1.524)
			(layers "F.Cu" "F.Mask" "F.Paste")
			(net "IO_EXP_HDD_FAULT_A0")
		)
		(pad "2" smd rect
			(at -2.92608 2.8194 90)
			(size 0.3556 1.524)
			(layers "F.Cu" "F.Mask" "F.Paste")
			(net "IO_EXP_HDD_FAULT_A1")
		)
		(pad "3" smd rect
			(at -2.27584 2.8194 90)
			(size 0.3556 1.524)
			(layers "F.Cu" "F.Mask" "F.Paste")
			(net "IO_EXP_HDD_FAULT_A2")
		)
		(pad "4" smd rect
			(at -1.6256 2.8194 90)
			(size 0.3556 1.524)
			(layers "F.Cu" "F.Mask" "F.Paste")
			(net "SAS_HDD_LED_0")
		)
		(pad "5" smd rect
			(at -0.97536 2.8194 90)
			(size 0.3556 1.524)
			(layers "F.Cu" "F.Mask" "F.Paste")
			(net "SAS_HDD_LED_1")
		)
		(pad "6" smd rect
			(at -0.32512 2.8194 90)
			(size 0.3556 1.524)
			(layers "F.Cu" "F.Mask" "F.Paste")
			(net "SAS_HDD_LED_2")
		)
		(pad "7" smd rect
			(at 0.32512 2.8194 90)
			(size 0.3556 1.524)
			(layers "F.Cu" "F.Mask" "F.Paste")
			(net "SAS_HDD_LED_3")
		)
		(pad "8" smd rect
			(at 0.97536 2.8194 90)
			(size 0.3556 1.524)
			(layers "F.Cu" "F.Mask" "F.Paste")
			(net "SAS_HDD_LED_4")
		)
		(pad "9" smd rect
			(at 1.6256 2.8194 90)
			(size 0.3556 1.524)
			(layers "F.Cu" "F.Mask" "F.Paste")
			(net "SAS_HDD_LED_5")
		)
		(pad "10" smd rect
			(at 2.27584 2.8194 90)
			(size 0.3556 1.524)
			(layers "F.Cu" "F.Mask" "F.Paste")
			(net "SAS_HDD_LED_6")
		)
		(pad "11" smd rect
			(at 2.92608 2.8194 90)
			(size 0.3556 1.524)
			(layers "F.Cu" "F.Mask" "F.Paste")
			(net "SAS_HDD_LED_7")
		)
		(pad "12" smd rect
			(at 3.57632 2.8194 90)
			(size 0.3556 1.524)
			(layers "F.Cu" "F.Mask" "F.Paste")
			(net "GND")
		)
		(pad "13" smd rect
			(at 3.57632 -2.8194 90)
			(size 0.3556 1.524)
			(layers "F.Cu" "F.Mask" "F.Paste")
			(net "SAS_HDD_LED_8")
		)
		(pad "14" smd rect
			(at 2.92608 -2.8194 90)
			(size 0.3556 1.524)
			(layers "F.Cu" "F.Mask" "F.Paste")
			(net "SAS_HDD_LED_9")
		)
		(pad "15" smd rect
			(at 2.27584 -2.8194 90)
			(size 0.3556 1.524)
			(layers "F.Cu" "F.Mask" "F.Paste")
			(net "SAS_HDD_LED_10")
		)
		(pad "16" smd rect
			(at 1.6256 -2.8194 90)
			(size 0.3556 1.524)
			(layers "F.Cu" "F.Mask" "F.Paste")
			(net "SAS_HDD_LED_11")
		)
		(pad "17" smd rect
			(at 0.97536 -2.8194 90)
			(size 0.3556 1.524)
			(layers "F.Cu" "F.Mask" "F.Paste")
			(net "SAS_HDD_LED_12")
		)
		(pad "18" smd rect
			(at 0.32512 -2.8194 90)
			(size 0.3556 1.524)
			(layers "F.Cu" "F.Mask" "F.Paste")
			(net "SAS_HDD_LED_13")
		)
		(pad "19" smd rect
			(at -0.32512 -2.8194 90)
			(size 0.3556 1.524)
			(layers "F.Cu" "F.Mask" "F.Paste")
			(net "SAS_HDD_LED_14")
		)
		(pad "20" smd rect
			(at -0.97536 -2.8194 90)
			(size 0.3556 1.524)
			(layers "F.Cu" "F.Mask" "F.Paste")
			(net "SAS_HDD_LED_15")
		)
		(pad "21" smd rect
			(at -1.6256 -2.8194 90)
			(size 0.3556 1.524)
			(layers "F.Cu" "F.Mask" "F.Paste")
			(net "I2C_IO_EXP_RESET#_FLT")
		)
		(pad "22" smd rect
			(at -2.27584 -2.8194 90)
			(size 0.3556 1.524)
			(layers "F.Cu" "F.Mask" "F.Paste")
			(net "FAULT_SCL")
		)
		(pad "23" smd rect
			(at -2.92608 -2.8194 90)
			(size 0.3556 1.524)
			(layers "F.Cu" "F.Mask" "F.Paste")
			(net "FAULT_SDA")
		)
		(pad "24" smd rect
			(at -3.57632 -2.8194 90)
			(size 0.3556 1.524)
			(layers "F.Cu" "F.Mask" "F.Paste")
			(net "P3V3_STBY")
		)
	)
	(footprint ""
		(layer "F.Cu")
		(at 100.85197 -78.105)
		(property "Reference" "STP98"
			(at 0 0 0)
			(layer "F.SilkS")
			(hide yes)
			(effects
				(font
					(size 1.27 1.27)
				)
			)
		)
		(property "Value" "TPAD28"
			(at 0.0127 -1.8034 0)
			(unlocked yes)
			(layer "F.Fab")
			(hide yes)
			(effects
				(font
					(size 1.016 1.016)
					(thickness 0.1524)
				)
			)
		)
		(property "Device Type" "TPAD28"
			(at 0.0127 -3.3274 0)
			(unlocked yes)
			(layer "F.Fab")
			(hide yes)
			(effects
				(font
					(size 1.016 1.016)
					(thickness 0.1524)
				)
			)
		)
		(duplicate_pad_numbers_are_jumpers no)
		(fp_poly
			(pts
				(arc
					(start 0.3556 0)
					(mid -0.3556 0)
					(end 0.3556 0)
				)
			)
			(stroke
				(width 0)
				(type default)
			)
			(fill no)
			(layer "F.CrtYd")
		)
		(fp_poly
			(pts
				(arc
					(start 0.6096 0)
					(mid -0.6096 0)
					(end 0.6096 0)
				)
			)
			(stroke
				(width 0)
				(type default)
			)
			(fill no)
			(layer "F.Fab")
		)
		(pad "1" smd circle
			(at 0 0)
			(size 0.7112 0.7112)
			(layers "F.Cu" "F.Mask" "F.Paste")
			(net "LSI_PROCMON")
		)
	)
	(footprint ""
		(layer "F.Cu")
		(at 87.757 -226.822 -90)
		(property "Reference" "SR266"
			(at 0 0 270)
			(layer "F.SilkS")
			(hide yes)
			(effects
				(font
					(size 1.27 1.27)
				)
			)
		)
		(property "Value" "4K7R2F-GP"
			(at 0.064008 -3.993896 270)
			(unlocked yes)
			(layer "F.Fab")
			(hide yes)
			(effects
				(font
					(size 1.016 1.016)
					(thickness 0.1524)
				)
			)
		)
		(property "Device Type" "R402H16"
			(at 0.064008 -5.517896 270)
			(unlocked yes)
			(layer "F.Fab")
			(hide yes)
			(effects
				(font
					(size 1.016 1.016)
					(thickness 0.1524)
				)
			)
		)
		(duplicate_pad_numbers_are_jumpers no)
		(fp_line
			(start -0.508 -0.9398)
			(end -0.508 0.9398)
			(stroke
				(width 0.1524)
				(type default)
			)
			(layer "F.SilkS")
		)
		(fp_line
			(start 0.508 -0.9398)
			(end -0.508 -0.9398)
			(stroke
				(width 0.1524)
				(type default)
			)
			(layer "F.SilkS")
		)
		(fp_rect
			(start -0.508 0.9398)
			(end 0.508 -0.9398)
			(stroke
				(width 0)
				(type default)
			)
			(fill no)
			(layer "F.CrtYd")
		)
		(fp_rect
			(start -0.508 0.9398)
			(end 0.508 -0.9398)
			(stroke
				(width 0)
				(type default)
			)
			(fill no)
			(layer "F.Fab")
		)
		(pad "1" smd custom
			(at 0 -0.4445 270)
			(size 0.1397 0.1397)
			(layers "F.Cu" "F.Mask" "F.Paste")
			(net "I2C_IO_EXP_RESET#_FLT")
			(options
				(clearance outline)
				(anchor circle)
			)
			(primitives
				(gr_poly
					(pts
						(arc
							(start -0.1778 -0.2794)
							(mid -0.249642 -0.249642)
							(end -0.2794 -0.1778)
						)
						(arc
							(start -0.2794 0.1778)
							(mid -0.249642 0.249642)
							(end -0.1778 0.2794)
						)
						(arc
							(start 0.1778 0.2794)
							(mid 0.249642 0.249642)
							(end 0.2794 0.1778)
						)
						(arc
							(start 0.2794 -0.1778)
							(mid 0.249642 -0.249642)
							(end 0.1778 -0.2794)
						)
					)
					(width 0)
					(fill yes)
				)
			)
		)
		(pad "2" smd custom
			(at 0 0.4445 270)
			(size 0.1397 0.1397)
			(layers "F.Cu" "F.Mask" "F.Paste")
			(net "P3V3_STBY")
			(options
				(clearance outline)
				(anchor circle)
			)
			(primitives
				(gr_poly
					(pts
						(arc
							(start -0.1778 -0.2794)
							(mid -0.249642 -0.249642)
							(end -0.2794 -0.1778)
						)
						(arc
							(start -0.2794 0.1778)
							(mid -0.249642 0.249642)
							(end -0.1778 0.2794)
						)
						(arc
							(start 0.1778 0.2794)
							(mid 0.249642 0.249642)
							(end 0.2794 0.1778)
						)
						(arc
							(start 0.2794 -0.1778)
							(mid 0.249642 -0.249642)
							(end 0.1778 -0.2794)
						)
					)
					(width 0)
					(fill yes)
				)
			)
		)
	)
)
